# T6G (Grand Teton) — schematic netlist excerpt (pin names and nets, part order shuffled) for the footprints in the layout excerpt that follows; sources: Cadence DE-HDL packaged netlist, KiCad conversion of 04192023_DAF0TMB3IC0_F0TG_MB_C_brd_V02_OCP.brd

C6058  Q_CAP  0.001UF 50V 10% X7R  pkg C0402  page 177 : A = P1V2_AUX ; B = GND
R784  Q_RES  4.7K 5% EMPTY  pkg 0201LF  page 331 : A = P1V8_CPU1_RT_1D ; B = TEST0_RT_CPU1_P1
C620  Q_CAP  1UF 4V 20% X6S  pkg 0201  page 290 : A = P0V9_CPU0_RT1_2A ; B = GND
C2076  Q_CAP_DIFFBUS  DIFF BUS_0.22UF 6.3V 20% X6S  pkg C0201  page 53 : \1\ = P3E_CPU1_P5_TX_C_DN<0> ; \2\ = P3E_CPU1_P5_TX_DN<0>

(kicad_pcb
	(version 20260206)
	(generator "pcbnew")
	(generator_version "10.0")
	(general
		(thickness 1.6)
		(legacy_teardrops no)
	)
	(paper "A4")
	(title_block
		(title "04192023_DAF0TMB3IC0_F0TG_MB_C_brd_V02_OCP.brd")
		(comment 1 "Grand Teton / footprints 6264-6267 of 8354")
	)
	(layers
		(0 "F.Cu" signal "TOP")
		(4 "In1.Cu" signal "GND")
		(6 "In2.Cu" signal "IN1")
		(8 "In3.Cu" signal "GND1")
		(10 "In4.Cu" signal "IN2")
		(12 "In5.Cu" signal "GND2")
		(14 "In6.Cu" signal "IN3")
		(16 "In7.Cu" signal "GND3")
		(18 "In8.Cu" signal "VCC")
		(20 "In9.Cu" signal "VCC1")
		(22 "In10.Cu" signal "GND4")
		(24 "In11.Cu" signal "IN4")
		(26 "In12.Cu" signal "GND5")
		(28 "In13.Cu" signal "IN5")
		(30 "In14.Cu" signal "GND6")
		(32 "In15.Cu" signal "IN6")
		(34 "In16.Cu" signal "GND7")
		(2 "B.Cu" signal "BOTTOM")
		(9 "F.Adhes" user "F.Adhesive")
		(11 "B.Adhes" user "B.Adhesive")
		(13 "F.Paste" user "Package Geometry/Pastemask Top")
		(15 "B.Paste" user "Package Geometry/Pastemask Bottom")
		(5 "F.SilkS" user "Ref Des/Silkscreen Top")
		(7 "B.SilkS" user "Ref Des/Silkscreen Bottom")
		(1 "F.Mask" user "Board Geometry/Soldermask Top")
		(3 "B.Mask" user "Board Geometry/Soldermask Bottom")
		(17 "Dwgs.User" user "User.Drawings")
		(19 "Cmts.User" user "User.Comments")
		(21 "Eco1.User" user "User.Eco1")
		(23 "Eco2.User" user "User.Eco2")
		(25 "Edge.Cuts" user "Board Geometry/Outline")
		(27 "Margin" user)
		(31 "F.CrtYd" user "Package Geometry/Place Bound Top")
		(29 "B.CrtYd" user "Package Geometry/Place Bound Bottom")
		(35 "F.Fab" user "Ref Des/Assembly Top")
		(33 "B.Fab" user "Ref Des/Assembly Bottom")
	)
	(footprint ""
		(layer "B.Cu")
		(at 333.945992 -395.43228)
		(property "Reference" "C620"
			(at 0 0 0)
			(layer "B.SilkS")
			(hide yes)
			(effects
				(font
					(size 1.27 1.27)
				)
				(justify mirror)
			)
		)
		(property "Value" ""
			(at 0 0 0)
			(layer "B.Fab")
			(effects
				(font
					(size 1.27 1.27)
				)
				(justify mirror)
			)
		)
		(duplicate_pad_numbers_are_jumpers no)
		(fp_line
			(start -0.299974 -0.150114)
			(end -0.299974 0.150114)
			(stroke
				(width 0.1)
				(type default)
			)
			(layer "B.Fab")
		)
		(fp_line
			(start -0.299974 0.150114)
			(end 0.299974 0.150114)
			(stroke
				(width 0.1)
				(type default)
			)
			(layer "B.Fab")
		)
		(fp_line
			(start 0.299974 -0.150114)
			(end -0.299974 -0.150114)
			(stroke
				(width 0.1)
				(type default)
			)
			(layer "B.Fab")
		)
		(fp_line
			(start 0.299974 0.150114)
			(end 0.299974 -0.150114)
			(stroke
				(width 0.1)
				(type default)
			)
			(layer "B.Fab")
		)
		(pad "1" smd rect
			(at 0.2667 0 180)
			(size 0.3048 0.381)
			(layers "B.Cu" "B.Mask" "B.Paste")
			(net "P0V9_CPU0_RT1_2A")
		)
		(pad "2" smd rect
			(at -0.2667 0 180)
			(size 0.3048 0.381)
			(layers "B.Cu" "B.Mask" "B.Paste")
			(net "GND")
		)
	)
	(footprint ""
		(layer "B.Cu")
		(at 51.734974 -416.929316)
		(property "Reference" "C2076"
			(at 0 0 0)
			(layer "B.SilkS")
			(hide yes)
			(effects
				(font
					(size 1.27 1.27)
				)
				(justify mirror)
			)
		)
		(property "Value" ""
			(at 0 0 0)
			(layer "B.Fab")
			(effects
				(font
					(size 1.27 1.27)
				)
				(justify mirror)
			)
		)
		(duplicate_pad_numbers_are_jumpers no)
		(fp_line
			(start -0.299974 -0.150114)
			(end -0.299974 0.150114)
			(stroke
				(width 0.1)
				(type default)
			)
			(layer "B.Fab")
		)
		(fp_line
			(start -0.299974 0.150114)
			(end 0.299974 0.150114)
			(stroke
				(width 0.1)
				(type default)
			)
			(layer "B.Fab")
		)
		(fp_line
			(start 0.299974 -0.150114)
			(end -0.299974 -0.150114)
			(stroke
				(width 0.1)
				(type default)
			)
			(layer "B.Fab")
		)
		(fp_line
			(start 0.299974 0.150114)
			(end 0.299974 -0.150114)
			(stroke
				(width 0.1)
				(type default)
			)
			(layer "B.Fab")
		)
		(pad "1" smd rect
			(at 0.2667 0 180)
			(size 0.3048 0.381)
			(layers "B.Cu" "B.Mask" "B.Paste")
			(net "P3E_CPU1_P5_TX_C_DN<0>")
		)
		(pad "2" smd rect
			(at -0.2667 0 180)
			(size 0.3048 0.381)
			(layers "B.Cu" "B.Mask" "B.Paste")
			(net "P3E_CPU1_P5_TX_DN<0>")
		)
	)
	(footprint ""
		(layer "B.Cu")
		(at 138.65352 -38.733222 180)
		(property "Reference" "C6058"
			(at 0 0 0)
			(layer "B.SilkS")
			(hide yes)
			(effects
				(font
					(size 1.27 1.27)
				)
				(justify mirror)
			)
		)
		(property "Value" ""
			(at 0 0 0)
			(layer "B.Fab")
			(effects
				(font
					(size 1.27 1.27)
				)
				(justify mirror)
			)
		)
		(duplicate_pad_numbers_are_jumpers no)
		(fp_line
			(start 0.7874 0.4064)
			(end 0.7874 -0.4064)
			(stroke
				(width 0.1524)
				(type default)
			)
			(layer "B.SilkS")
		)
		(fp_line
			(start 0.7874 -0.4064)
			(end -0.7874 -0.4064)
			(stroke
				(width 0.1524)
				(type default)
			)
			(layer "B.SilkS")
		)
		(fp_line
			(start -0.7874 0.4064)
			(end 0.7874 0.4064)
			(stroke
				(width 0.1524)
				(type default)
			)
			(layer "B.SilkS")
		)
		(fp_line
			(start -0.7874 -0.4064)
			(end -0.7874 0.4064)
			(stroke
				(width 0.1524)
				(type default)
			)
			(layer "B.SilkS")
		)
		(fp_line
			(start 0.67945 0.3048)
			(end 0.67945 -0.305054)
			(stroke
				(width 0.1)
				(type default)
			)
			(layer "B.Fab")
		)
		(fp_line
			(start 0.67945 -0.305054)
			(end 0.12065 -0.305054)
			(stroke
				(width 0.1)
				(type default)
			)
			(layer "B.Fab")
		)
		(fp_line
			(start 0.12065 0.3048)
			(end 0.67945 0.3048)
			(stroke
				(width 0.1)
				(type default)
			)
			(layer "B.Fab")
		)
		(fp_line
			(start 0.12065 0.2794)
			(end 0.12065 0.3048)
			(stroke
				(width 0.1)
				(type default)
			)
			(layer "B.Fab")
		)
		(fp_line
			(start 0.12065 -0.2794)
			(end -0.12065 -0.2794)
			(stroke
				(width 0.1)
				(type default)
			)
			(layer "B.Fab")
		)
		(fp_line
			(start 0.12065 -0.305054)
			(end 0.12065 -0.2794)
			(stroke
				(width 0.1)
				(type default)
			)
			(layer "B.Fab")
		)
		(fp_line
			(start -0.120396 0.3048)
			(end -0.120396 0.2794)
			(stroke
				(width 0.1)
				(type default)
			)
			(layer "B.Fab")
		)
		(fp_line
			(start -0.120396 0.2794)
			(end 0.12065 0.2794)
			(stroke
				(width 0.1)
				(type default)
			)
			(layer "B.Fab")
		)
		(fp_line
			(start -0.12065 -0.2794)
			(end -0.12065 -0.3048)
			(stroke
				(width 0.1)
				(type default)
			)
			(layer "B.Fab")
		)
		(fp_line
			(start -0.12065 -0.3048)
			(end -0.67945 -0.3048)
			(stroke
				(width 0.1)
				(type default)
			)
			(layer "B.Fab")
		)
		(fp_line
			(start -0.67945 0.3048)
			(end -0.120396 0.3048)
			(stroke
				(width 0.1)
				(type default)
			)
			(layer "B.Fab")
		)
		(fp_line
			(start -0.67945 -0.3048)
			(end -0.67945 0.3048)
			(stroke
				(width 0.1)
				(type default)
			)
			(layer "B.Fab")
		)
		(pad "1" smd circle
			(at 0.40005 0)
			(size 0 0)
			(layers "B.Cu" "B.Mask" "B.Paste")
			(net "P1V2_AUX")
		)
		(pad "2" smd circle
			(at -0.40005 0)
			(size 0 0)
			(layers "B.Cu" "B.Mask" "B.Paste")
			(net "GND")
		)
	)
	(footprint ""
		(layer "B.Cu")
		(at 74.5236 -385.58216 180)
		(property "Reference" "R784"
			(at 0 0 0)
			(layer "B.SilkS")
			(hide yes)
			(effects
				(font
					(size 1.27 1.27)
				)
				(justify mirror)
			)
		)
		(property "Value" ""
			(at 0 0 0)
			(layer "B.Fab")
			(effects
				(font
					(size 1.27 1.27)
				)
				(justify mirror)
			)
		)
		(duplicate_pad_numbers_are_jumpers no)
		(fp_line
			(start 0.32512 0.175006)
			(end 0.32512 -0.175006)
			(stroke
				(width 0.1)
				(type default)
			)
			(layer "B.Fab")
		)
		(fp_line
			(start 0.32512 -0.175006)
			(end -0.32512 -0.175006)
			(stroke
				(width 0.1)
				(type default)
			)
			(layer "B.Fab")
		)
		(fp_line
			(start -0.32512 0.175006)
			(end 0.32512 0.175006)
			(stroke
				(width 0.1)
				(type default)
			)
			(layer "B.Fab")
		)
		(fp_line
			(start -0.32512 -0.175006)
			(end -0.32512 0.175006)
			(stroke
				(width 0.1)
				(type default)
			)
			(layer "B.Fab")
		)
		(pad "1" smd rect
			(at 0.2667 0)
			(size 0.3048 0.381)
			(layers "B.Cu" "B.Mask" "B.Paste")
			(net "P1V8_CPU1_RT_1D")
		)
		(pad "2" smd rect
			(at -0.2667 0 180)
			(size 0.3048 0.381)
			(layers "B.Cu" "B.Mask" "B.Paste")
			(net "TEST0_RT_CPU1_P1")
		)
	)
)
